FILE_TYPE=LIBRARY_PARTS;
primitive 'PI4ULS3V304AZMAEX';
  pin
    'A1':
      PIN_NUMBER='(2)';
      BIDIRECTIONAL='TRUE';
      INPUT_LOAD='(-0.01,0.01)';
      OUTPUT_LOAD='(1.0,-1.0)';
    'A2':
      PIN_NUMBER='(3)';
      BIDIRECTIONAL='TRUE';
      INPUT_LOAD='(-0.01,0.01)';
      OUTPUT_LOAD='(1.0,-1.0)';
    'A3':
      PIN_NUMBER='(4)';
      BIDIRECTIONAL='TRUE';
      INPUT_LOAD='(-0.01,0.01)';
      OUTPUT_LOAD='(1.0,-1.0)';
    'VCCB':
      PIN_NUMBER='(11)';
      PINUSE='POWER';
      NO_LOAD_CHECK='Both';
      NO_IO_CHECK='Both';
      NO_ASSERT_CHECK='TRUE';
      NO_DIR_CHECK='TRUE';
      ALLOW_CONNECT='TRUE';
    'EN':
      PIN_NUMBER='(12)';
      INPUT_LOAD='(-0.01,0.01)';
    'A4':
      PIN_NUMBER='(5)';
      BIDIRECTIONAL='TRUE';
      INPUT_LOAD='(-0.01,0.01)';
      OUTPUT_LOAD='(1.0,-1.0)';
    'VCCA':
      PIN_NUMBER='(1)';
      PINUSE='POWER';
      NO_LOAD_CHECK='Both';
      NO_IO_CHECK='Both';
      NO_ASSERT_CHECK='TRUE';
      NO_DIR_CHECK='TRUE';
      ALLOW_CONNECT='TRUE';
    'B1':
      PIN_NUMBER='(10)';
      BIDIRECTIONAL='TRUE';
      INPUT_LOAD='(-0.01,0.01)';
      OUTPUT_LOAD='(1.0,-1.0)';
    'B2':
      PIN_NUMBER='(9)';
      BIDIRECTIONAL='TRUE';
      INPUT_LOAD='(-0.01,0.01)';
      OUTPUT_LOAD='(1.0,-1.0)';
    'B3':
      PIN_NUMBER='(8)';
      BIDIRECTIONAL='TRUE';
      INPUT_LOAD='(-0.01,0.01)';
      OUTPUT_LOAD='(1.0,-1.0)';
    'B4':
      PIN_NUMBER='(7)';
      BIDIRECTIONAL='TRUE';
      INPUT_LOAD='(-0.01,0.01)';
      OUTPUT_LOAD='(1.0,-1.0)';
    'GND':
      PIN_NUMBER='(6)';
      PINUSE='POWER';
      NO_LOAD_CHECK='Both';
      NO_IO_CHECK='Both';
      NO_ASSERT_CHECK='TRUE';
      NO_DIR_CHECK='TRUE';
      ALLOW_CONNECT='TRUE';
  end_pin;
  body
    PART_NAME='PI4ULS3V304AZMAEX';
    BODY_NAME='PI4ULS3V304AZMAEX';
    PHYS_DES_PREFIX='U';
    CLASS='IC';
  end_body;
end_primitive;

END.
